# BASEBOARD_FAB2 (Tioga Pass) — schematic netlist excerpt (pin names and nets, part order shuffled) for the footprints in the layout excerpt that follows; sources: Cadence DE-HDL packaged netlist, KiCad conversion of Wiwynn_Tioga_Pass_MB.brd

C4M2  CAP_A  47UF 4V 20% X5R  pkg 0603V  page 220 : A = PVDDQ_DEF ; B = GND
C3P3  CAP_A  1.0UF 6.3V 10% X6S  pkg 0402V  page 211 : A = VR_PVCCIO_CPU0_VDD ; B = GND
R25W110  RES  4.75K 1% EMPTY  pkg 0402  page 150 : A = P3V3_STBY ; B = TP_RGMII2TXD2_GPIOU2

(kicad_pcb
	(version 20260206)
	(generator "pcbnew")
	(generator_version "10.0")
	(general
		(thickness 1.6)
		(legacy_teardrops no)
	)
	(paper "A4")
	(title_block
		(title "Wiwynn_Tioga_Pass_MB.brd")
		(comment 1 "Tioga Pass / footprints 3429-3431 of 4770")
	)
	(layers
		(0 "F.Cu" signal "TOP")
		(4 "In1.Cu" signal "L2GND")
		(6 "In2.Cu" signal "L3")
		(8 "In3.Cu" signal "L4GND")
		(10 "In4.Cu" signal "L5")
		(12 "In5.Cu" signal "L6GND")
		(14 "In6.Cu" signal "L7VCC")
		(16 "In7.Cu" signal "L8VCC")
		(18 "In8.Cu" signal "L9GND")
		(20 "In9.Cu" signal "L10")
		(22 "In10.Cu" signal "L11GND")
		(24 "In11.Cu" signal "L12")
		(26 "In12.Cu" signal "L13GND")
		(2 "B.Cu" signal "BOTTOM")
		(9 "F.Adhes" user "F.Adhesive")
		(11 "B.Adhes" user "B.Adhesive")
		(13 "F.Paste" user "Package Geometry/Pastemask Top")
		(15 "B.Paste" user "Package Geometry/Pastemask Bottom")
		(5 "F.SilkS" user "Ref Des/Silkscreen Top")
		(7 "B.SilkS" user "Ref Des/Silkscreen Bottom")
		(1 "F.Mask" user "Board Geometry/Soldermask Top")
		(3 "B.Mask" user "Board Geometry/Soldermask Bottom")
		(17 "Dwgs.User" user "User.Drawings")
		(19 "Cmts.User" user "User.Comments")
		(21 "Eco1.User" user "User.Eco1")
		(23 "Eco2.User" user "User.Eco2")
		(25 "Edge.Cuts" user "Board Geometry/Outline")
		(27 "Margin" user)
		(31 "F.CrtYd" user "Package Geometry/Place Bound Top")
		(29 "B.CrtYd" user "Package Geometry/Place Bound Bottom")
		(35 "F.Fab" user "Ref Des/Assembly Top")
		(33 "B.Fab" user "Ref Des/Assembly Bottom")
	)
	(footprint ""
		(layer "B.Cu")
		(at 404.0251 -29.337 90)
		(property "Reference" "R25W110"
			(at 0.8382 -0.67818 90)
			(unlocked yes)
			(layer "B.SilkS")
			(effects
				(font
					(size 0.4064 0.254)
					(thickness 0.1524)
				)
				(justify left mirror)
			)
		)
		(property "Value" ""
			(at 0 0 90)
			(layer "B.Fab")
			(effects
				(font
					(size 1.27 1.27)
				)
				(justify mirror)
			)
		)
		(duplicate_pad_numbers_are_jumpers no)
		(fp_poly
			(pts
				(xy 0.2794 -0.1016) (xy -0.2794 -0.1016) (xy -0.2794 0.9906) (xy 0.2794 0.9906)
			)
			(stroke
				(width 0)
				(type default)
			)
			(fill no)
			(layer "B.CrtYd")
		)
		(fp_line
			(start 0.2794 -0.1016)
			(end 0.2794 0.9906)
			(stroke
				(width 0.1)
				(type default)
			)
			(layer "B.Fab")
		)
		(fp_line
			(start -0.2794 -0.1016)
			(end 0.2794 -0.1016)
			(stroke
				(width 0.1)
				(type default)
			)
			(layer "B.Fab")
		)
		(fp_line
			(start 0.2794 0.9906)
			(end -0.2794 0.9906)
			(stroke
				(width 0.1)
				(type default)
			)
			(layer "B.Fab")
		)
		(fp_line
			(start -0.2794 0.9906)
			(end -0.2794 -0.1016)
			(stroke
				(width 0.1)
				(type default)
			)
			(layer "B.Fab")
		)
		(pad "1" smd rect
			(at 0 0 270)
			(size 0.508 0.508)
			(layers "B.Cu" "B.Mask" "B.Paste")
			(net "P3V3_STBY")
		)
		(pad "2" smd rect
			(at 0 0.889 270)
			(size 0.508 0.508)
			(layers "B.Cu" "B.Mask" "B.Paste")
			(net "TP_RGMII2TXD2_GPIOU2")
		)
		(zone
			(layer "B.Cu")
			(hatch none 0.5)
			(connect_pads
				(clearance 0)
			)
			(min_thickness 0.25)
			(keepout
				(tracks allowed)
				(vias not_allowed)
				(pads allowed)
				(copperpour not_allowed)
				(footprints allowed)
			)
			(placement
				(enabled no)
				(sheetname "")
			)
			(fill
				(thermal_gap 0.5)
				(thermal_bridge_width 0.5)
				(island_removal_mode 0)
			)
			(polygon
				(pts
					(xy 404.2791 -29.591) (xy 404.2791 -29.083) (xy 404.6601 -29.083) (xy 404.6601 -29.591)
				)
			)
		)
		(zone
			(layer "B.Cu")
			(hatch none 0.5)
			(connect_pads
				(clearance 0)
			)
			(min_thickness 0.25)
			(keepout
				(tracks not_allowed)
				(vias allowed)
				(pads allowed)
				(copperpour not_allowed)
				(footprints allowed)
			)
			(placement
				(enabled no)
				(sheetname "")
			)
			(fill
				(thermal_gap 0.5)
				(thermal_bridge_width 0.5)
				(island_removal_mode 0)
			)
			(polygon
				(pts
					(xy 404.6601 -29.591) (xy 404.6601 -29.083) (xy 404.2791 -29.083) (xy 404.2791 -29.591)
				)
			)
		)
	)
	(footprint ""
		(layer "B.Cu")
		(at 276.381464 -135.4074 90)
		(property "Reference" "C4M2"
			(at -1.848866 0.752348 90)
			(unlocked yes)
			(layer "B.SilkS")
			(effects
				(font
					(size 1.27 0.9652)
					(thickness 0.1524)
				)
				(justify mirror)
			)
		)
		(property "Value" ""
			(at 0 0 90)
			(layer "B.Fab")
			(effects
				(font
					(size 1.27 1.27)
				)
				(justify mirror)
			)
		)
		(duplicate_pad_numbers_are_jumpers no)
		(fp_rect
			(start 0.500126 1.598422)
			(end -0.500126 -0.201422)
			(stroke
				(width 0)
				(type default)
			)
			(fill no)
			(layer "B.CrtYd")
		)
		(fp_line
			(start 0.500126 -0.201422)
			(end -0.500126 -0.201422)
			(stroke
				(width 0.1)
				(type default)
			)
			(layer "B.Fab")
		)
		(fp_line
			(start -0.500126 -0.201422)
			(end -0.500126 1.598422)
			(stroke
				(width 0.1)
				(type default)
			)
			(layer "B.Fab")
		)
		(fp_line
			(start 0.500126 1.598422)
			(end 0.500126 -0.201422)
			(stroke
				(width 0.1)
				(type default)
			)
			(layer "B.Fab")
		)
		(fp_line
			(start -0.500126 1.598422)
			(end 0.500126 1.598422)
			(stroke
				(width 0.1)
				(type default)
			)
			(layer "B.Fab")
		)
		(pad "1" smd rect
			(at 0 0)
			(size 0.889 0.9906)
			(layers "B.Cu" "B.Mask" "B.Paste")
			(net "PVDDQ_DEF")
		)
		(pad "2" smd rect
			(at 0 1.397)
			(size 0.889 0.9906)
			(layers "B.Cu" "B.Mask" "B.Paste")
			(net "GND")
		)
		(zone
			(layer "B.Cu")
			(hatch none 0.5)
			(connect_pads
				(clearance 0)
			)
			(min_thickness 0.25)
			(keepout
				(tracks allowed)
				(vias not_allowed)
				(pads allowed)
				(copperpour not_allowed)
				(footprints allowed)
			)
			(placement
				(enabled no)
				(sheetname "")
			)
			(fill
				(thermal_gap 0.5)
				(thermal_bridge_width 0.5)
				(island_removal_mode 0)
			)
			(polygon
				(pts
					(xy 277.333964 -135.9027) (xy 276.825964 -135.9027) (xy 276.825964 -134.9121) (xy 277.333964 -134.9121)
				)
			)
		)
		(zone
			(layer "B.Cu")
			(hatch none 0.5)
			(connect_pads
				(clearance 0)
			)
			(min_thickness 0.25)
			(keepout
				(tracks not_allowed)
				(vias allowed)
				(pads allowed)
				(copperpour not_allowed)
				(footprints allowed)
			)
			(placement
				(enabled no)
				(sheetname "")
			)
			(fill
				(thermal_gap 0.5)
				(thermal_bridge_width 0.5)
				(island_removal_mode 0)
			)
			(polygon
				(pts
					(xy 277.333964 -135.9027) (xy 276.825964 -135.9027) (xy 276.825964 -134.9121) (xy 277.333964 -134.9121)
				)
			)
		)
	)
	(footprint ""
		(layer "B.Cu")
		(at 350.9772 -84.328 90)
		(property "Reference" "C3P3"
			(at 0 0 90)
			(layer "B.SilkS")
			(hide yes)
			(effects
				(font
					(size 1.27 1.27)
				)
				(justify mirror)
			)
		)
		(property "Value" ""
			(at 0 0 90)
			(layer "B.Fab")
			(effects
				(font
					(size 1.27 1.27)
				)
				(justify mirror)
			)
		)
		(duplicate_pad_numbers_are_jumpers no)
		(fp_poly
			(pts
				(xy -0.3048 -0.1016) (xy -0.3048 0.9906) (xy 0.3048 0.9906) (xy 0.3048 -0.1016)
			)
			(stroke
				(width 0)
				(type default)
			)
			(fill no)
			(layer "B.CrtYd")
		)
		(fp_line
			(start 0.3048 -0.1016)
			(end 0.3048 0.9906)
			(stroke
				(width 0.1)
				(type default)
			)
			(layer "B.Fab")
		)
		(fp_line
			(start -0.3048 -0.1016)
			(end 0.3048 -0.1016)
			(stroke
				(width 0.1)
				(type default)
			)
			(layer "B.Fab")
		)
		(fp_line
			(start 0.3048 0.9906)
			(end -0.3048 0.9906)
			(stroke
				(width 0.1)
				(type default)
			)
			(layer "B.Fab")
		)
		(fp_line
			(start -0.3048 0.9906)
			(end -0.3048 -0.1016)
			(stroke
				(width 0.1)
				(type default)
			)
			(layer "B.Fab")
		)
		(pad "1" smd rect
			(at 0 0 270)
			(size 0.508 0.508)
			(layers "B.Cu" "B.Mask" "B.Paste")
			(net "VR_PVCCIO_CPU0_VDD")
		)
		(pad "2" smd rect
			(at 0 0.889 270)
			(size 0.508 0.508)
			(layers "B.Cu" "B.Mask" "B.Paste")
			(net "GND")
		)
		(zone
			(layer "B.Cu")
			(hatch none 0.5)
			(connect_pads
				(clearance 0)
			)
			(min_thickness 0.25)
			(keepout
				(tracks allowed)
				(vias not_allowed)
				(pads allowed)
				(copperpour not_allowed)
				(footprints allowed)
			)
			(placement
				(enabled no)
				(sheetname "")
			)
			(fill
				(thermal_gap 0.5)
				(thermal_bridge_width 0.5)
				(island_removal_mode 0)
			)
			(polygon
				(pts
					(xy 351.2312 -84.582) (xy 351.2312 -84.074) (xy 351.6122 -84.074) (xy 351.6122 -84.582)
				)
			)
		)
		(zone
			(layer "B.Cu")
			(hatch none 0.5)
			(connect_pads
				(clearance 0)
			)
			(min_thickness 0.25)
			(keepout
				(tracks not_allowed)
				(vias allowed)
				(pads allowed)
				(copperpour not_allowed)
				(footprints allowed)
			)
			(placement
				(enabled no)
				(sheetname "")
			)
			(fill
				(thermal_gap 0.5)
				(thermal_bridge_width 0.5)
				(island_removal_mode 0)
			)
			(polygon
				(pts
					(xy 351.6122 -84.582) (xy 351.6122 -84.074) (xy 351.2312 -84.074) (xy 351.2312 -84.582)
				)
			)
		)
	)
)
